# BASEBOARD_FAB2 (Tioga Pass) — schematic netlist excerpt (pin names and nets, part order shuffled) for the footprints in the layout excerpt that follows; sources: Cadence DE-HDL packaged netlist, KiCad conversion of Wiwynn_Tioga_Pass_MB.brd

C25W77  CAP  12.0PF 50V 5% COG  pkg 0402LF  page 252 : A = V_IO_R_J ; B = GND
C5P20  CAP  100UF 4V 20% X5R  pkg 0805  page 42 : A = PVCCMCP_CPU0 ; B = GND
C6L3  CAP  10UF 4V 20% X6S  pkg 0603LF  page 222 : A = PVDDQ_DEF ; B = GND

(kicad_pcb
	(version 20260206)
	(generator "pcbnew")
	(generator_version "10.0")
	(general
		(thickness 1.6)
		(legacy_teardrops no)
	)
	(paper "A4")
	(title_block
		(title "Wiwynn_Tioga_Pass_MB.brd")
		(comment 1 "Tioga Pass / footprints 3276-3278 of 4770")
	)
	(layers
		(0 "F.Cu" signal "TOP")
		(4 "In1.Cu" signal "L2GND")
		(6 "In2.Cu" signal "L3")
		(8 "In3.Cu" signal "L4GND")
		(10 "In4.Cu" signal "L5")
		(12 "In5.Cu" signal "L6GND")
		(14 "In6.Cu" signal "L7VCC")
		(16 "In7.Cu" signal "L8VCC")
		(18 "In8.Cu" signal "L9GND")
		(20 "In9.Cu" signal "L10")
		(22 "In10.Cu" signal "L11GND")
		(24 "In11.Cu" signal "L12")
		(26 "In12.Cu" signal "L13GND")
		(2 "B.Cu" signal "BOTTOM")
		(9 "F.Adhes" user "F.Adhesive")
		(11 "B.Adhes" user "B.Adhesive")
		(13 "F.Paste" user "Package Geometry/Pastemask Top")
		(15 "B.Paste" user "Package Geometry/Pastemask Bottom")
		(5 "F.SilkS" user "Ref Des/Silkscreen Top")
		(7 "B.SilkS" user "Ref Des/Silkscreen Bottom")
		(1 "F.Mask" user "Board Geometry/Soldermask Top")
		(3 "B.Mask" user "Board Geometry/Soldermask Bottom")
		(17 "Dwgs.User" user "User.Drawings")
		(19 "Cmts.User" user "User.Comments")
		(21 "Eco1.User" user "User.Eco1")
		(23 "Eco2.User" user "User.Eco2")
		(25 "Edge.Cuts" user "Board Geometry/Outline")
		(27 "Margin" user)
		(31 "F.CrtYd" user "Package Geometry/Place Bound Top")
		(29 "B.CrtYd" user "Package Geometry/Place Bound Bottom")
		(35 "F.Fab" user "Ref Des/Assembly Top")
		(33 "B.Fab" user "Ref Des/Assembly Bottom")
	)
	(footprint ""
		(layer "B.Cu")
		(at 182.169562 -150.876508)
		(property "Reference" "C6L3"
			(at 0 0 0)
			(layer "B.SilkS")
			(hide yes)
			(effects
				(font
					(size 1.27 1.27)
				)
				(justify mirror)
			)
		)
		(property "Value" ""
			(at 0 0 0)
			(layer "B.Fab")
			(effects
				(font
					(size 1.27 1.27)
				)
				(justify mirror)
			)
		)
		(duplicate_pad_numbers_are_jumpers no)
		(fp_rect
			(start 0.4953 -0.2032)
			(end -0.4953 1.6002)
			(stroke
				(width 0)
				(type default)
			)
			(fill no)
			(layer "B.CrtYd")
		)
		(fp_line
			(start -0.4953 -0.2032)
			(end -0.4953 1.6002)
			(stroke
				(width 0.1)
				(type default)
			)
			(layer "B.Fab")
		)
		(fp_line
			(start -0.4953 1.6002)
			(end 0.4953 1.6002)
			(stroke
				(width 0.1)
				(type default)
			)
			(layer "B.Fab")
		)
		(fp_line
			(start 0.4953 -0.2032)
			(end -0.4953 -0.2032)
			(stroke
				(width 0.1)
				(type default)
			)
			(layer "B.Fab")
		)
		(fp_line
			(start 0.4953 1.6002)
			(end 0.4953 -0.2032)
			(stroke
				(width 0.1)
				(type default)
			)
			(layer "B.Fab")
		)
		(pad "1" smd rect
			(at 0 0 180)
			(size 0.762 0.889)
			(layers "B.Cu" "B.Mask" "B.Paste")
			(net "PVDDQ_DEF")
		)
		(pad "2" smd rect
			(at 0 1.397 180)
			(size 0.762 0.889)
			(layers "B.Cu" "B.Mask" "B.Paste")
			(net "GND")
		)
		(zone
			(layer "B.Cu")
			(hatch none 0.5)
			(connect_pads
				(clearance 0)
			)
			(min_thickness 0.25)
			(keepout
				(tracks not_allowed)
				(vias allowed)
				(pads allowed)
				(copperpour not_allowed)
				(footprints allowed)
			)
			(placement
				(enabled no)
				(sheetname "")
			)
			(fill
				(thermal_gap 0.5)
				(thermal_bridge_width 0.5)
				(island_removal_mode 0)
			)
			(polygon
				(pts
					(xy 182.550562 -150.432008) (xy 181.788562 -150.432008) (xy 181.788562 -149.924008) (xy 182.550562 -149.924008)
				)
			)
		)
	)
	(footprint ""
		(layer "B.Cu")
		(at 420.624 -25.654)
		(property "Reference" "C25W77"
			(at 0.8382 -0.67818 0)
			(unlocked yes)
			(layer "B.SilkS")
			(effects
				(font
					(size 0.4064 0.254)
					(thickness 0.1524)
				)
				(justify left mirror)
			)
		)
		(property "Value" ""
			(at 0 0 0)
			(layer "B.Fab")
			(effects
				(font
					(size 1.27 1.27)
				)
				(justify mirror)
			)
		)
		(duplicate_pad_numbers_are_jumpers no)
		(fp_poly
			(pts
				(xy -0.3048 -0.1016) (xy -0.3048 0.9906) (xy 0.3048 0.9906) (xy 0.3048 -0.1016)
			)
			(stroke
				(width 0)
				(type default)
			)
			(fill no)
			(layer "B.CrtYd")
		)
		(fp_line
			(start -0.3048 -0.1016)
			(end 0.3048 -0.1016)
			(stroke
				(width 0.1)
				(type default)
			)
			(layer "B.Fab")
		)
		(fp_line
			(start -0.3048 0.9906)
			(end -0.3048 -0.1016)
			(stroke
				(width 0.1)
				(type default)
			)
			(layer "B.Fab")
		)
		(fp_line
			(start 0.3048 -0.1016)
			(end 0.3048 0.9906)
			(stroke
				(width 0.1)
				(type default)
			)
			(layer "B.Fab")
		)
		(fp_line
			(start 0.3048 0.9906)
			(end -0.3048 0.9906)
			(stroke
				(width 0.1)
				(type default)
			)
			(layer "B.Fab")
		)
		(pad "1" smd rect
			(at 0 0 180)
			(size 0.508 0.508)
			(layers "B.Cu" "B.Mask" "B.Paste")
			(net "V_IO_R_J")
		)
		(pad "2" smd rect
			(at 0 0.889 180)
			(size 0.508 0.508)
			(layers "B.Cu" "B.Mask" "B.Paste")
			(net "GND")
		)
		(zone
			(layer "B.Cu")
			(hatch none 0.5)
			(connect_pads
				(clearance 0)
			)
			(min_thickness 0.25)
			(keepout
				(tracks allowed)
				(vias not_allowed)
				(pads allowed)
				(copperpour not_allowed)
				(footprints allowed)
			)
			(placement
				(enabled no)
				(sheetname "")
			)
			(fill
				(thermal_gap 0.5)
				(thermal_bridge_width 0.5)
				(island_removal_mode 0)
			)
			(polygon
				(pts
					(xy 420.878 -25.4) (xy 420.37 -25.4) (xy 420.37 -25.019) (xy 420.878 -25.019)
				)
			)
		)
		(zone
			(layer "B.Cu")
			(hatch none 0.5)
			(connect_pads
				(clearance 0)
			)
			(min_thickness 0.25)
			(keepout
				(tracks not_allowed)
				(vias allowed)
				(pads allowed)
				(copperpour not_allowed)
				(footprints allowed)
			)
			(placement
				(enabled no)
				(sheetname "")
			)
			(fill
				(thermal_gap 0.5)
				(thermal_bridge_width 0.5)
				(island_removal_mode 0)
			)
			(polygon
				(pts
					(xy 420.878 -25.019) (xy 420.37 -25.019) (xy 420.37 -25.4) (xy 420.878 -25.4)
				)
			)
		)
	)
	(footprint ""
		(layer "B.Cu")
		(at 271.350486 -77.82814)
		(property "Reference" "C5P20"
			(at 0 0 0)
			(layer "B.SilkS")
			(hide yes)
			(effects
				(font
					(size 1.27 1.27)
				)
				(justify mirror)
			)
		)
		(property "Value" ""
			(at 0 0 0)
			(layer "B.Fab")
			(effects
				(font
					(size 1.27 1.27)
				)
				(justify mirror)
			)
		)
		(duplicate_pad_numbers_are_jumpers no)
		(fp_poly
			(pts
				(xy 0.7239 -0.2159) (xy -0.7239 -0.2159) (xy -0.7239 1.9939) (xy 0.7239 1.9939)
			)
			(stroke
				(width 0)
				(type default)
			)
			(fill no)
			(layer "B.CrtYd")
		)
		(fp_line
			(start -0.7239 -0.2159)
			(end 0.7239 -0.2159)
			(stroke
				(width 0.1)
				(type default)
			)
			(layer "B.Fab")
		)
		(fp_line
			(start -0.7239 1.9939)
			(end -0.7239 -0.2159)
			(stroke
				(width 0.1)
				(type default)
			)
			(layer "B.Fab")
		)
		(fp_line
			(start 0.7239 -0.2159)
			(end 0.7239 1.9939)
			(stroke
				(width 0.1)
				(type default)
			)
			(layer "B.Fab")
		)
		(fp_line
			(start 0.7239 1.9939)
			(end -0.7239 1.9939)
			(stroke
				(width 0.1)
				(type default)
			)
			(layer "B.Fab")
		)
		(pad "1" smd rect
			(at 0 0 180)
			(size 1.27 1.016)
			(layers "B.Cu" "B.Mask" "B.Paste")
			(net "PVCCMCP_CPU0")
		)
		(pad "2" smd rect
			(at 0 1.778 180)
			(size 1.27 1.016)
			(layers "B.Cu" "B.Mask" "B.Paste")
			(net "GND")
		)
		(zone
			(layer "B.Cu")
			(hatch none 0.5)
			(connect_pads
				(clearance 0)
			)
			(min_thickness 0.25)
			(keepout
				(tracks not_allowed)
				(vias allowed)
				(pads allowed)
				(copperpour not_allowed)
				(footprints allowed)
			)
			(placement
				(enabled no)
				(sheetname "")
			)
			(fill
				(thermal_gap 0.5)
				(thermal_bridge_width 0.5)
				(island_removal_mode 0)
			)
			(polygon
				(pts
					(xy 271.985486 -77.32014) (xy 270.715486 -77.32014) (xy 270.715486 -76.55814) (xy 271.985486 -76.55814)
				)
			)
		)
	)
)
